# Bryce Canyon_IOM_M2_Stackup.xlsx — PCB Test Plan_HVM(0-90) (pcb-stackup)
|  | Board vendor give feedback of quantity in yellow columns based on the AQL table or description. |  |  |  |  |  |  |  |  |  |  |  |  |  |  |
|  | Wiwynn PM give feedback in blue columns |  |  |  |  |  |  |  |  |  |  |  |  |  |  |
| Person to be informed : PCB vendor, EE, SI, PM, PSM, Buyer, SQM |  |  |  |  |  |  |  |  |  |  |  |  |  |  |  |
| Simple flow : SI (test requirements) -> PM/AM (Total PCBS demand) -> Buyer -> Board Vendor (yellow column feedback) -> Buyer -> Person to be informed (Check and Track) |  |  |  |  |  |  |  |  |  |  |  |  |  |  |  |
| PO(purchase order) : If there are many POs for this PCB, 1st sample quantity is based on 1st PO, 2nd sample quantity is based on 2nd PO. |  |  |  |  |  |  |  |  |  |  |  |  |  |  |  |
| Project Name | PCB name | PCB# (1XXXX-XX) | Product Stage | Batch# | PCB Vendor | PCBs Demand | Delta-L Coupon (PCB Vendor) | Delta-L Coupon (3rd Party Lab) | Impedance Coupon (PCB Vendor) | In-board trace correlation (PCB Vendor) | X-section Analysis (PCB Vendor) | IST (3rd Party Lab) | Resin Void (PCB Vendor) | IPC-6012D (3rd Party Lab) | Note 1 |
| Bryce Canyon | IOM M2 | 16342-2 | HVM(0-90 days) | N/A |  |  | Yes | Yes | Yes | Yes | No | Yes | No | No | Need Test? (Yes, No) |
| Tracking Code On Both Of Coupon And PCB |  |  |  |  |  |  | Follow rules of board vendor | Follow rules of board vendor | Follow rules of board vendor | Follow rules of board vendor |  | Follow rules of board vendor |  |  |  |
| Test Item Acceptance Criteria |  |  |  |  |  |  | Failure Rate ≦0.3% | Failure Rate ≦0.3% | Cpk≧1.0 | Fail : 0 Variation ≦5% |  | Fail: 0 |  |  |  |
| Test Item Sampling Quantity |  |  |  |  |  |  | AQL 1, level 1 | 30 pcs | AQL 1, level 1 | AQL 1, level 1 |  | 5 pcs/production lot, with max total of 30 pcs |  |  |  |
| Test Time (working days) |  |  |  |  |  |  | 5 | 5 | 5 | 5 |  | 20+ |  |  |  |
| Test Item Shipping Quantity |  |  |  |  |  |  |  | 30 pcs |  |  |  | 5 pcs/production lot, with max total of 30 pcs |  |  |  |
| Shipping Address |  |  |  |  |  |  |  | 8F, 90, Sec. 1, Xintai 5th Rd., Xizhi Dist., New Taipei City 22102, Taiwan, R.O.C. |  |  |  | 8F, 90, Sec. 1, Xintai 5th Rd., Xizhi Dist., New Taipei City 22102, Taiwan, R.O.C. |  |  |  |
| Receiver Name |  |  |  |  |  |  |  | Karol Lai |  |  |  | Karol Lai |  |  |  |
| Receiver Phone# |  |  |  |  |  |  |  | 886-2-6612-7507 |  |  |  | 886-2-6612-7507 |  |  |  |
